# BASEBOARD_FAB2 (Tioga Pass) — schematic netlist excerpt (pin names and nets, part order shuffled) for the footprints in the layout excerpt that follows; sources: Cadence DE-HDL packaged netlist, KiCad conversion of Wiwynn_Tioga_Pass_MB.brd

C2G7  CAP  100UF 4V 20% X5R  pkg 0805  page 225 : A = PVDDQ_GHJ ; B = GND
C5F1  CAP_A  47UF 4V 20% X5R  pkg 0603V  page 217 : A = PVDDQ_ABC ; B = GND
R9E9  RES  33.2 1% CHIP  pkg 0402  page 139 : A = SPI_NIC_MOSI_R ; B = SPI_NIC_MOSI

(kicad_pcb
	(version 20260206)
	(generator "pcbnew")
	(generator_version "10.0")
	(general
		(thickness 1.6)
		(legacy_teardrops no)
	)
	(paper "A4")
	(title_block
		(title "Wiwynn_Tioga_Pass_MB.brd")
		(comment 1 "Tioga Pass / footprints 244-246 of 4770")
	)
	(layers
		(0 "F.Cu" signal "TOP")
		(4 "In1.Cu" signal "L2GND")
		(6 "In2.Cu" signal "L3")
		(8 "In3.Cu" signal "L4GND")
		(10 "In4.Cu" signal "L5")
		(12 "In5.Cu" signal "L6GND")
		(14 "In6.Cu" signal "L7VCC")
		(16 "In7.Cu" signal "L8VCC")
		(18 "In8.Cu" signal "L9GND")
		(20 "In9.Cu" signal "L10")
		(22 "In10.Cu" signal "L11GND")
		(24 "In11.Cu" signal "L12")
		(26 "In12.Cu" signal "L13GND")
		(2 "B.Cu" signal "BOTTOM")
		(9 "F.Adhes" user "F.Adhesive")
		(11 "B.Adhes" user "B.Adhesive")
		(13 "F.Paste" user "Package Geometry/Pastemask Top")
		(15 "B.Paste" user "Package Geometry/Pastemask Bottom")
		(5 "F.SilkS" user "Ref Des/Silkscreen Top")
		(7 "B.SilkS" user "Ref Des/Silkscreen Bottom")
		(1 "F.Mask" user "Board Geometry/Soldermask Top")
		(3 "B.Mask" user "Board Geometry/Soldermask Bottom")
		(17 "Dwgs.User" user "User.Drawings")
		(19 "Cmts.User" user "User.Comments")
		(21 "Eco1.User" user "User.Eco1")
		(23 "Eco2.User" user "User.Eco2")
		(25 "Edge.Cuts" user "Board Geometry/Outline")
		(27 "Margin" user)
		(31 "F.CrtYd" user "Package Geometry/Place Bound Top")
		(29 "B.CrtYd" user "Package Geometry/Place Bound Bottom")
		(35 "F.Fab" user "Ref Des/Assembly Top")
		(33 "B.Fab" user "Ref Des/Assembly Bottom")
	)
	(footprint ""
		(layer "F.Cu")
		(at 243.735606 -26.591006 -45)
		(property "Reference" "C5F1"
			(at 0 0 315)
			(layer "F.SilkS")
			(hide yes)
			(effects
				(font
					(size 1.27 1.27)
				)
			)
		)
		(property "Value" ""
			(at 0 0 315)
			(layer "F.Fab")
			(effects
				(font
					(size 1.27 1.27)
				)
			)
		)
		(duplicate_pad_numbers_are_jumpers no)
		(fp_poly
			(pts
				(xy -0.500021 -0.201359) (xy 0.500231 -0.201359) (xy 0.500231 1.598486) (xy -0.500021 1.598486)
			)
			(stroke
				(width 0)
				(type default)
			)
			(fill no)
			(layer "F.CrtYd")
		)
		(fp_line
			(start -0.500021 1.598486)
			(end -0.5002 -0.201337)
			(stroke
				(width 0.1)
				(type default)
			)
			(layer "F.Fab")
		)
		(fp_line
			(start 0.500021 1.598486)
			(end -0.500021 1.598486)
			(stroke
				(width 0.1)
				(type default)
			)
			(layer "F.Fab")
		)
		(fp_line
			(start -0.5002 -0.201337)
			(end 0.5002 -0.201337)
			(stroke
				(width 0.1)
				(type default)
			)
			(layer "F.Fab")
		)
		(fp_line
			(start 0.5002 -0.201337)
			(end 0.500021 1.598486)
			(stroke
				(width 0.1)
				(type default)
			)
			(layer "F.Fab")
		)
		(pad "1" smd rect
			(at 0 0 225)
			(size 0.889 0.9906)
			(layers "F.Cu" "F.Mask" "F.Paste")
			(net "PVDDQ_ABC")
		)
		(pad "2" smd rect
			(at 0 1.397 225)
			(size 0.889 0.9906)
			(layers "F.Cu" "F.Mask" "F.Paste")
			(net "GND")
		)
		(zone
			(layer "F.Cu")
			(hatch none 0.5)
			(connect_pads
				(clearance 0)
			)
			(min_thickness 0.25)
			(keepout
				(tracks not_allowed)
				(vias allowed)
				(pads allowed)
				(copperpour not_allowed)
				(footprints allowed)
			)
			(placement
				(enabled no)
				(sheetname "")
			)
			(fill
				(thermal_gap 0.5)
				(thermal_bridge_width 0.5)
				(island_removal_mode 0)
			)
			(polygon
				(pts
					(xy 242.711732 -26.267664) (xy 243.412192 -25.567204) (xy 243.771402 -25.926414) (xy 243.070942 -26.626874)
				)
			)
		)
		(zone
			(layer "F.Cu")
			(hatch none 0.5)
			(connect_pads
				(clearance 0)
			)
			(min_thickness 0.25)
			(keepout
				(tracks allowed)
				(vias not_allowed)
				(pads allowed)
				(copperpour not_allowed)
				(footprints allowed)
			)
			(placement
				(enabled no)
				(sheetname "")
			)
			(fill
				(thermal_gap 0.5)
				(thermal_bridge_width 0.5)
				(island_removal_mode 0)
			)
			(polygon
				(pts
					(xy 242.711732 -26.267664) (xy 243.412192 -25.567204) (xy 243.771402 -25.926414) (xy 243.070942 -26.626874)
				)
			)
		)
	)
	(footprint ""
		(layer "F.Cu")
		(at 94.343728 -13.004292 90)
		(property "Reference" "C2G7"
			(at 0 0 90)
			(layer "F.SilkS")
			(hide yes)
			(effects
				(font
					(size 1.27 1.27)
				)
			)
		)
		(property "Value" ""
			(at 0 0 90)
			(layer "F.Fab")
			(effects
				(font
					(size 1.27 1.27)
				)
			)
		)
		(duplicate_pad_numbers_are_jumpers no)
		(fp_poly
			(pts
				(xy -0.7239 -0.2159) (xy 0.7239 -0.2159) (xy 0.7239 1.9939) (xy -0.7239 1.9939)
			)
			(stroke
				(width 0)
				(type default)
			)
			(fill no)
			(layer "F.CrtYd")
		)
		(fp_line
			(start 0.7239 -0.2159)
			(end -0.7239 -0.2159)
			(stroke
				(width 0.1)
				(type default)
			)
			(layer "F.Fab")
		)
		(fp_line
			(start -0.7239 -0.2159)
			(end -0.7239 1.9939)
			(stroke
				(width 0.1)
				(type default)
			)
			(layer "F.Fab")
		)
		(fp_line
			(start 0.7239 1.9939)
			(end 0.7239 -0.2159)
			(stroke
				(width 0.1)
				(type default)
			)
			(layer "F.Fab")
		)
		(fp_line
			(start -0.7239 1.9939)
			(end 0.7239 1.9939)
			(stroke
				(width 0.1)
				(type default)
			)
			(layer "F.Fab")
		)
		(pad "1" smd rect
			(at 0 0 90)
			(size 1.27 1.016)
			(layers "F.Cu" "F.Mask" "F.Paste")
			(net "PVDDQ_GHJ")
		)
		(pad "2" smd rect
			(at 0 1.778 90)
			(size 1.27 1.016)
			(layers "F.Cu" "F.Mask" "F.Paste")
			(net "GND")
		)
		(zone
			(layer "F.Cu")
			(hatch none 0.5)
			(connect_pads
				(clearance 0)
			)
			(min_thickness 0.25)
			(keepout
				(tracks not_allowed)
				(vias allowed)
				(pads allowed)
				(copperpour not_allowed)
				(footprints allowed)
			)
			(placement
				(enabled no)
				(sheetname "")
			)
			(fill
				(thermal_gap 0.5)
				(thermal_bridge_width 0.5)
				(island_removal_mode 0)
			)
			(polygon
				(pts
					(xy 94.851728 -12.369292) (xy 94.851728 -13.639292) (xy 95.613728 -13.639292) (xy 95.613728 -12.369292)
				)
			)
		)
	)
	(footprint ""
		(layer "F.Cu")
		(at 490.2581 -45.9994 90)
		(property "Reference" "R9E9"
			(at 0 0 90)
			(layer "F.SilkS")
			(hide yes)
			(effects
				(font
					(size 1.27 1.27)
				)
			)
		)
		(property "Value" ""
			(at 0 0 90)
			(layer "F.Fab")
			(effects
				(font
					(size 1.27 1.27)
				)
			)
		)
		(duplicate_pad_numbers_are_jumpers no)
		(fp_poly
			(pts
				(xy -0.2794 -0.1016) (xy 0.2794 -0.1016) (xy 0.2794 0.9906) (xy -0.2794 0.9906)
			)
			(stroke
				(width 0)
				(type default)
			)
			(fill no)
			(layer "F.CrtYd")
		)
		(fp_line
			(start 0.2794 -0.1016)
			(end -0.2794 -0.1016)
			(stroke
				(width 0.1)
				(type default)
			)
			(layer "F.Fab")
		)
		(fp_line
			(start -0.2794 -0.1016)
			(end -0.2794 0.9906)
			(stroke
				(width 0.1)
				(type default)
			)
			(layer "F.Fab")
		)
		(fp_line
			(start 0.2794 0.9906)
			(end 0.2794 -0.1016)
			(stroke
				(width 0.1)
				(type default)
			)
			(layer "F.Fab")
		)
		(fp_line
			(start -0.2794 0.9906)
			(end 0.2794 0.9906)
			(stroke
				(width 0.1)
				(type default)
			)
			(layer "F.Fab")
		)
		(pad "1" smd rect
			(at 0 0 90)
			(size 0.508 0.508)
			(layers "F.Cu" "F.Mask" "F.Paste")
			(net "SPI_NIC_MOSI_R")
		)
		(pad "2" smd rect
			(at 0 0.889 90)
			(size 0.508 0.508)
			(layers "F.Cu" "F.Mask" "F.Paste")
			(net "SPI_NIC_MOSI")
		)
		(zone
			(layer "F.Cu")
			(hatch none 0.5)
			(connect_pads
				(clearance 0)
			)
			(min_thickness 0.25)
			(keepout
				(tracks allowed)
				(vias not_allowed)
				(pads allowed)
				(copperpour not_allowed)
				(footprints allowed)
			)
			(placement
				(enabled no)
				(sheetname "")
			)
			(fill
				(thermal_gap 0.5)
				(thermal_bridge_width 0.5)
				(island_removal_mode 0)
			)
			(polygon
				(pts
					(xy 490.5121 -45.7454) (xy 490.5121 -46.2534) (xy 490.8931 -46.2534) (xy 490.8931 -45.7454)
				)
			)
		)
		(zone
			(layer "F.Cu")
			(hatch none 0.5)
			(connect_pads
				(clearance 0)
			)
			(min_thickness 0.25)
			(keepout
				(tracks not_allowed)
				(vias allowed)
				(pads allowed)
				(copperpour not_allowed)
				(footprints allowed)
			)
			(placement
				(enabled no)
				(sheetname "")
			)
			(fill
				(thermal_gap 0.5)
				(thermal_bridge_width 0.5)
				(island_removal_mode 0)
			)
			(polygon
				(pts
					(xy 490.8931 -45.7454) (xy 490.8931 -46.2534) (xy 490.5121 -46.2534) (xy 490.5121 -45.7454)
				)
			)
		)
	)
)
